(kicad_pcb
	(version 20260206)
	(generator "pcbnew")
	(generator_version "10.0")
	(general
		(thickness 1.6)
		(legacy_teardrops no)
	)
	(paper "A4")
	(title_block
		(title "Bryce Canyon_IOM_IOC_16318-2_OCP.brd")
		(comment 1 "Bryce Canyon / footprints 693-700 of 1605")
	)
	(layers
		(0 "F.Cu" signal "TOP")
		(4 "In1.Cu" signal "L2GND")
		(6 "In2.Cu" signal "L3")
		(8 "In3.Cu" signal "L4VCC")
		(10 "In4.Cu" signal "L5VCC")
		(12 "In5.Cu" signal "L6")
		(14 "In6.Cu" signal "L7GND")
		(2 "B.Cu" signal "BOTTOM")
		(9 "F.Adhes" user "F.Adhesive")
		(11 "B.Adhes" user "B.Adhesive")
		(13 "F.Paste" user "Package Geometry/Pastemask Top")
		(15 "B.Paste" user "Package Geometry/Pastemask Bottom")
		(5 "F.SilkS" user "Ref Des/Silkscreen Top")
		(7 "B.SilkS" user "Ref Des/Silkscreen Bottom")
		(1 "F.Mask" user "Board Geometry/Soldermask Top")
		(3 "B.Mask" user "Board Geometry/Soldermask Bottom")
		(17 "Dwgs.User" user "User.Drawings")
		(19 "Cmts.User" user "User.Comments")
		(21 "Eco1.User" user "User.Eco1")
		(23 "Eco2.User" user "User.Eco2")
		(25 "Edge.Cuts" user "Board Geometry/Outline")
		(27 "Margin" user)
		(31 "F.CrtYd" user "Package Geometry/Place Bound Top")
		(29 "B.CrtYd" user "Package Geometry/Place Bound Bottom")
		(35 "F.Fab" user "Ref Des/Assembly Top")
		(33 "B.Fab" user "Ref Des/Assembly Bottom")
	)
	(footprint ""
		(layer "F.Cu")
		(at 158.06674 -39.99738)
		(property "Reference" "TP183"
			(at 0 0 0)
			(layer "F.SilkS")
			(hide yes)
			(effects
				(font
					(size 1.27 1.27)
				)
			)
		)
		(property "Value" "TPAD28-2-GP"
			(at -0.0127 -1.6637 0)
			(unlocked yes)
			(layer "F.Fab")
			(hide yes)
			(effects
				(font
					(size 1.016 1.016)
					(thickness 0.1524)
				)
			)
		)
		(property "Device Type" "TPAD28"
			(at -0.0127 -3.1877 0)
			(unlocked yes)
			(layer "F.Fab")
			(hide yes)
			(effects
				(font
					(size 1.016 1.016)
					(thickness 0.1524)
				)
			)
		)
		(duplicate_pad_numbers_are_jumpers no)
		(fp_poly
			(pts
				(arc
					(start 0.3556 0)
					(mid -0.3556 0)
					(end 0.3556 0)
				)
			)
			(stroke
				(width 0)
				(type default)
			)
			(fill no)
			(layer "F.CrtYd")
		)
		(fp_poly
			(pts
				(arc
					(start 0.6096 0)
					(mid -0.6096 0)
					(end 0.6096 0)
				)
			)
			(stroke
				(width 0)
				(type default)
			)
			(fill no)
			(layer "F.Fab")
		)
		(pad "1" smd circle
			(at 0 0)
			(size 0.7112 0.7112)
			(layers "F.Cu" "F.Mask" "F.Paste")
			(net "ZDEF_EXTB_TP_D1")
		)
	)
	(footprint ""
		(layer "F.Cu")
		(at 189.357 -129.1844 90)
		(property "Reference" "R566"
			(at 0 0 90)
			(layer "F.SilkS")
			(hide yes)
			(effects
				(font
					(size 1.27 1.27)
				)
			)
		)
		(property "Value" "453R2F-1-GP"
			(at 0.064008 -3.993896 90)
			(unlocked yes)
			(layer "F.Fab")
			(hide yes)
			(effects
				(font
					(size 1.016 1.016)
					(thickness 0.1524)
				)
			)
		)
		(property "Device Type" "R402H16"
			(at 0.064008 -5.517896 90)
			(unlocked yes)
			(layer "F.Fab")
			(hide yes)
			(effects
				(font
					(size 1.016 1.016)
					(thickness 0.1524)
				)
			)
		)
		(duplicate_pad_numbers_are_jumpers no)
		(fp_line
			(start 0.508 -0.9398)
			(end -0.508 -0.9398)
			(stroke
				(width 0.1524)
				(type default)
			)
			(layer "F.SilkS")
		)
		(fp_line
			(start -0.508 -0.9398)
			(end -0.508 0.9398)
			(stroke
				(width 0.1524)
				(type default)
			)
			(layer "F.SilkS")
		)
		(fp_rect
			(start -0.508 0.9398)
			(end 0.508 -0.9398)
			(stroke
				(width 0)
				(type default)
			)
			(fill no)
			(layer "F.CrtYd")
		)
		(fp_rect
			(start -0.508 0.9398)
			(end 0.508 -0.9398)
			(stroke
				(width 0)
				(type default)
			)
			(fill no)
			(layer "F.Fab")
		)
		(pad "1" smd custom
			(at 0 -0.4445 90)
			(size 0.1397 0.1397)
			(layers "F.Cu" "F.Mask" "F.Paste")
			(net "VT235_VDES_RR")
			(options
				(clearance outline)
				(anchor circle)
			)
			(primitives
				(gr_poly
					(pts
						(arc
							(start -0.1778 -0.2794)
							(mid -0.249642 -0.249642)
							(end -0.2794 -0.1778)
						)
						(arc
							(start -0.2794 0.1778)
							(mid -0.249642 0.249642)
							(end -0.1778 0.2794)
						)
						(arc
							(start 0.1778 0.2794)
							(mid 0.249642 0.249642)
							(end 0.2794 0.1778)
						)
						(arc
							(start 0.2794 -0.1778)
							(mid 0.249642 -0.249642)
							(end 0.1778 -0.2794)
						)
					)
					(width 0)
					(fill yes)
				)
			)
		)
		(pad "2" smd custom
			(at 0 0.4445 90)
			(size 0.1397 0.1397)
			(layers "F.Cu" "F.Mask" "F.Paste")
			(net "VT235_VDES_RCC")
			(options
				(clearance outline)
				(anchor circle)
			)
			(primitives
				(gr_poly
					(pts
						(arc
							(start -0.1778 -0.2794)
							(mid -0.249642 -0.249642)
							(end -0.2794 -0.1778)
						)
						(arc
							(start -0.2794 0.1778)
							(mid -0.249642 0.249642)
							(end -0.1778 0.2794)
						)
						(arc
							(start 0.1778 0.2794)
							(mid 0.249642 0.249642)
							(end 0.2794 0.1778)
						)
						(arc
							(start 0.2794 -0.1778)
							(mid 0.249642 -0.249642)
							(end 0.1778 -0.2794)
						)
					)
					(width 0)
					(fill yes)
				)
			)
		)
	)
	(footprint ""
		(layer "F.Cu")
		(at 203.298552 -132.119624 180)
		(property "Reference" "C253"
			(at 0 0 180)
			(layer "F.SilkS")
			(hide yes)
			(effects
				(font
					(size 1.27 1.27)
				)
			)
		)
		(property "Value" "SC1U16V3KX-5GP"
			(at 0 -2.8194 180)
			(unlocked yes)
			(layer "F.Fab")
			(hide yes)
			(effects
				(font
					(size 1.016 1.016)
					(thickness 0.1524)
				)
			)
		)
		(property "Device Type" "C603H36"
			(at 0 -4.3434 180)
			(unlocked yes)
			(layer "F.Fab")
			(hide yes)
			(effects
				(font
					(size 1.016 1.016)
					(thickness 0.1524)
				)
			)
		)
		(duplicate_pad_numbers_are_jumpers no)
		(fp_line
			(start 0.508 0)
			(end -0.508 0)
			(stroke
				(width 0.2032)
				(type default)
			)
			(layer "F.SilkS")
		)
		(fp_rect
			(start -0.5842 1.3335)
			(end 0.5842 -1.3335)
			(stroke
				(width 0)
				(type default)
			)
			(fill no)
			(layer "F.CrtYd")
		)
		(fp_rect
			(start -0.5842 1.3335)
			(end 0.5842 -1.3335)
			(stroke
				(width 0)
				(type default)
			)
			(fill no)
			(layer "F.Fab")
		)
		(pad "1" smd custom
			(at 0 -0.762 180)
			(size 0.2159 0.2159)
			(layers "F.Cu" "F.Mask" "F.Paste")
			(net "TPS74801_1V5_BIAS")
			(options
				(clearance outline)
				(anchor circle)
			)
			(primitives
				(gr_poly
					(pts
						(arc
							(start -0.3302 -0.4318)
							(mid -0.402042 -0.402042)
							(end -0.4318 -0.3302)
						)
						(arc
							(start -0.4318 0.3302)
							(mid -0.402042 0.402042)
							(end -0.3302 0.4318)
						)
						(arc
							(start 0.3302 0.4318)
							(mid 0.402042 0.402042)
							(end 0.4318 0.3302)
						)
						(arc
							(start 0.4318 -0.3302)
							(mid 0.402042 -0.402042)
							(end 0.3302 -0.4318)
						)
					)
					(width 0)
					(fill yes)
				)
			)
		)
		(pad "2" smd custom
			(at 0 0.762 180)
			(size 0.2159 0.2159)
			(layers "F.Cu" "F.Mask" "F.Paste")
			(net "GND")
			(options
				(clearance outline)
				(anchor circle)
			)
			(primitives
				(gr_poly
					(pts
						(arc
							(start -0.3302 -0.4318)
							(mid -0.402042 -0.402042)
							(end -0.4318 -0.3302)
						)
						(arc
							(start -0.4318 0.3302)
							(mid -0.402042 0.402042)
							(end -0.3302 0.4318)
						)
						(arc
							(start 0.3302 0.4318)
							(mid 0.402042 0.402042)
							(end 0.4318 0.3302)
						)
						(arc
							(start 0.4318 -0.3302)
							(mid 0.402042 -0.402042)
							(end 0.3302 -0.4318)
						)
					)
					(width 0)
					(fill yes)
				)
			)
		)
	)
	(footprint ""
		(layer "F.Cu")
		(at 174.5742 -67.3354 90)
		(property "Reference" "R647"
			(at 0 0 90)
			(layer "F.SilkS")
			(hide yes)
			(effects
				(font
					(size 1.27 1.27)
				)
			)
		)
		(property "Value" "10KR2F-2-GP"
			(at 0.064008 -3.993896 90)
			(unlocked yes)
			(layer "F.Fab")
			(hide yes)
			(effects
				(font
					(size 1.016 1.016)
					(thickness 0.1524)
				)
			)
		)
		(property "Device Type" "R402H16"
			(at 0.064008 -5.517896 90)
			(unlocked yes)
			(layer "F.Fab")
			(hide yes)
			(effects
				(font
					(size 1.016 1.016)
					(thickness 0.1524)
				)
			)
		)
		(duplicate_pad_numbers_are_jumpers no)
		(fp_line
			(start 0.508 -0.9398)
			(end -0.508 -0.9398)
			(stroke
				(width 0.1524)
				(type default)
			)
			(layer "F.SilkS")
		)
		(fp_line
			(start -0.508 -0.9398)
			(end -0.508 0.9398)
			(stroke
				(width 0.1524)
				(type default)
			)
			(layer "F.SilkS")
		)
		(fp_rect
			(start -0.508 0.9398)
			(end 0.508 -0.9398)
			(stroke
				(width 0)
				(type default)
			)
			(fill no)
			(layer "F.CrtYd")
		)
		(fp_rect
			(start -0.508 0.9398)
			(end 0.508 -0.9398)
			(stroke
				(width 0)
				(type default)
			)
			(fill no)
			(layer "F.Fab")
		)
		(pad "1" smd custom
			(at 0 -0.4445 90)
			(size 0.1397 0.1397)
			(layers "F.Cu" "F.Mask" "F.Paste")
			(net "P1V8")
			(options
				(clearance outline)
				(anchor circle)
			)
			(primitives
				(gr_poly
					(pts
						(arc
							(start -0.1778 -0.2794)
							(mid -0.249642 -0.249642)
							(end -0.2794 -0.1778)
						)
						(arc
							(start -0.2794 0.1778)
							(mid -0.249642 0.249642)
							(end -0.1778 0.2794)
						)
						(arc
							(start 0.1778 0.2794)
							(mid 0.249642 0.249642)
							(end 0.2794 0.1778)
						)
						(arc
							(start 0.2794 -0.1778)
							(mid 0.249642 -0.249642)
							(end 0.1778 -0.2794)
						)
					)
					(width 0)
					(fill yes)
				)
			)
		)
		(pad "2" smd custom
			(at 0 0.4445 90)
			(size 0.1397 0.1397)
			(layers "F.Cu" "F.Mask" "F.Paste")
			(net "CP_DONE")
			(options
				(clearance outline)
				(anchor circle)
			)
			(primitives
				(gr_poly
					(pts
						(arc
							(start -0.1778 -0.2794)
							(mid -0.249642 -0.249642)
							(end -0.2794 -0.1778)
						)
						(arc
							(start -0.2794 0.1778)
							(mid -0.249642 0.249642)
							(end -0.1778 0.2794)
						)
						(arc
							(start 0.1778 0.2794)
							(mid 0.249642 0.249642)
							(end 0.2794 0.1778)
						)
						(arc
							(start 0.2794 -0.1778)
							(mid 0.249642 -0.249642)
							(end 0.1778 -0.2794)
						)
					)
					(width 0)
					(fill yes)
				)
			)
		)
	)
	(footprint ""
		(layer "F.Cu")
		(at 184.912 -147.8153)
		(property "Reference" "R478"
			(at 0 0 0)
			(layer "F.SilkS")
			(hide yes)
			(effects
				(font
					(size 1.27 1.27)
				)
			)
		)
		(property "Value" "10KR2F-2-GP"
			(at 0.064008 -3.993896 0)
			(unlocked yes)
			(layer "F.Fab")
			(hide yes)
			(effects
				(font
					(size 1.016 1.016)
					(thickness 0.1524)
				)
			)
		)
		(property "Device Type" "R402H16"
			(at 0.064008 -5.517896 0)
			(unlocked yes)
			(layer "F.Fab")
			(hide yes)
			(effects
				(font
					(size 1.016 1.016)
					(thickness 0.1524)
				)
			)
		)
		(duplicate_pad_numbers_are_jumpers no)
		(fp_line
			(start -0.508 -0.9398)
			(end -0.508 0.9398)
			(stroke
				(width 0.1524)
				(type default)
			)
			(layer "F.SilkS")
		)
		(fp_line
			(start 0.508 -0.9398)
			(end -0.508 -0.9398)
			(stroke
				(width 0.1524)
				(type default)
			)
			(layer "F.SilkS")
		)
		(fp_rect
			(start -0.508 0.9398)
			(end 0.508 -0.9398)
			(stroke
				(width 0)
				(type default)
			)
			(fill no)
			(layer "F.CrtYd")
		)
		(fp_rect
			(start -0.508 0.9398)
			(end 0.508 -0.9398)
			(stroke
				(width 0)
				(type default)
			)
			(fill no)
			(layer "F.Fab")
		)
		(pad "1" smd custom
			(at 0 -0.4445)
			(size 0.1397 0.1397)
			(layers "F.Cu" "F.Mask" "F.Paste")
			(net "P5V_VFB")
			(options
				(clearance outline)
				(anchor circle)
			)
			(primitives
				(gr_poly
					(pts
						(arc
							(start -0.1778 -0.2794)
							(mid -0.249642 -0.249642)
							(end -0.2794 -0.1778)
						)
						(arc
							(start -0.2794 0.1778)
							(mid -0.249642 0.249642)
							(end -0.1778 0.2794)
						)
						(arc
							(start 0.1778 0.2794)
							(mid 0.249642 0.249642)
							(end 0.2794 0.1778)
						)
						(arc
							(start 0.2794 -0.1778)
							(mid 0.249642 -0.249642)
							(end 0.1778 -0.2794)
						)
					)
					(width 0)
					(fill yes)
				)
			)
		)
		(pad "2" smd custom
			(at 0 0.4445)
			(size 0.1397 0.1397)
			(layers "F.Cu" "F.Mask" "F.Paste")
			(net "AGND_P5V")
			(options
				(clearance outline)
				(anchor circle)
			)
			(primitives
				(gr_poly
					(pts
						(arc
							(start -0.1778 -0.2794)
							(mid -0.249642 -0.249642)
							(end -0.2794 -0.1778)
						)
						(arc
							(start -0.2794 0.1778)
							(mid -0.249642 0.249642)
							(end -0.1778 0.2794)
						)
						(arc
							(start 0.1778 0.2794)
							(mid 0.249642 0.249642)
							(end 0.2794 0.1778)
						)
						(arc
							(start 0.2794 -0.1778)
							(mid 0.249642 -0.249642)
							(end 0.1778 -0.2794)
						)
					)
					(width 0)
					(fill yes)
				)
			)
		)
	)
	(footprint ""
		(layer "F.Cu")
		(at 63.422784 -141.417294 90)
		(property "Reference" "R198"
			(at 0 0 90)
			(layer "F.SilkS")
			(hide yes)
			(effects
				(font
					(size 1.27 1.27)
				)
			)
		)
		(property "Value" "1KR2F-3-GP"
			(at 0.064008 -3.993896 90)
			(unlocked yes)
			(layer "F.Fab")
			(hide yes)
			(effects
				(font
					(size 1.016 1.016)
					(thickness 0.1524)
				)
			)
		)
		(property "Device Type" "R402H16"
			(at 0.064008 -5.517896 90)
			(unlocked yes)
			(layer "F.Fab")
			(hide yes)
			(effects
				(font
					(size 1.016 1.016)
					(thickness 0.1524)
				)
			)
		)
		(duplicate_pad_numbers_are_jumpers no)
		(fp_line
			(start 0.508 -0.9398)
			(end -0.508 -0.9398)
			(stroke
				(width 0.1524)
				(type default)
			)
			(layer "F.SilkS")
		)
		(fp_line
			(start -0.508 -0.9398)
			(end -0.508 0.9398)
			(stroke
				(width 0.1524)
				(type default)
			)
			(layer "F.SilkS")
		)
		(fp_rect
			(start -0.508 0.9398)
			(end 0.508 -0.9398)
			(stroke
				(width 0)
				(type default)
			)
			(fill no)
			(layer "F.CrtYd")
		)
		(fp_rect
			(start -0.508 0.9398)
			(end 0.508 -0.9398)
			(stroke
				(width 0)
				(type default)
			)
			(fill no)
			(layer "F.Fab")
		)
		(pad "1" smd custom
			(at 0 -0.4445 90)
			(size 0.1397 0.1397)
			(layers "F.Cu" "F.Mask" "F.Paste")
			(net "I2C_EXP_RMT_SCL_OUT")
			(options
				(clearance outline)
				(anchor circle)
			)
			(primitives
				(gr_poly
					(pts
						(arc
							(start -0.1778 -0.2794)
							(mid -0.249642 -0.249642)
							(end -0.2794 -0.1778)
						)
						(arc
							(start -0.2794 0.1778)
							(mid -0.249642 0.249642)
							(end -0.1778 0.2794)
						)
						(arc
							(start 0.1778 0.2794)
							(mid 0.249642 0.249642)
							(end 0.2794 0.1778)
						)
						(arc
							(start 0.2794 -0.1778)
							(mid 0.249642 -0.249642)
							(end 0.1778 -0.2794)
						)
					)
					(width 0)
					(fill yes)
				)
			)
		)
		(pad "2" smd custom
			(at 0 0.4445 90)
			(size 0.1397 0.1397)
			(layers "F.Cu" "F.Mask" "F.Paste")
			(net "P3V3_STBY")
			(options
				(clearance outline)
				(anchor circle)
			)
			(primitives
				(gr_poly
					(pts
						(arc
							(start -0.1778 -0.2794)
							(mid -0.249642 -0.249642)
							(end -0.2794 -0.1778)
						)
						(arc
							(start -0.2794 0.1778)
							(mid -0.249642 0.249642)
							(end -0.1778 0.2794)
						)
						(arc
							(start 0.1778 0.2794)
							(mid 0.249642 0.249642)
							(end 0.2794 0.1778)
						)
						(arc
							(start 0.2794 -0.1778)
							(mid 0.249642 -0.249642)
							(end 0.1778 -0.2794)
						)
					)
					(width 0)
					(fill yes)
				)
			)
		)
	)
	(footprint ""
		(layer "F.Cu")
		(at 65.51168 -135.34898 -90)
		(property "Reference" "R731"
			(at 0 0 270)
			(layer "F.SilkS")
			(hide yes)
			(effects
				(font
					(size 1.27 1.27)
				)
			)
		)
		(property "Value" "0R2J-2-GP"
			(at 0.064008 -3.993896 270)
			(unlocked yes)
			(layer "F.Fab")
			(hide yes)
			(effects
				(font
					(size 1.016 1.016)
					(thickness 0.1524)
				)
			)
		)
		(property "Device Type" "R402H16"
			(at 0.064008 -5.517896 270)
			(unlocked yes)
			(layer "F.Fab")
			(hide yes)
			(effects
				(font
					(size 1.016 1.016)
					(thickness 0.1524)
				)
			)
		)
		(duplicate_pad_numbers_are_jumpers no)
		(fp_line
			(start -0.508 -0.9398)
			(end -0.508 0.9398)
			(stroke
				(width 0.1524)
				(type default)
			)
			(layer "F.SilkS")
		)
		(fp_line
			(start 0.508 -0.9398)
			(end -0.508 -0.9398)
			(stroke
				(width 0.1524)
				(type default)
			)
			(layer "F.SilkS")
		)
		(fp_rect
			(start -0.508 0.9398)
			(end 0.508 -0.9398)
			(stroke
				(width 0)
				(type default)
			)
			(fill no)
			(layer "F.CrtYd")
		)
		(fp_rect
			(start -0.508 0.9398)
			(end 0.508 -0.9398)
			(stroke
				(width 0)
				(type default)
			)
			(fill no)
			(layer "F.Fab")
		)
		(pad "1" smd custom
			(at 0 -0.4445 270)
			(size 0.1397 0.1397)
			(layers "F.Cu" "F.Mask" "F.Paste")
			(net "COMP_SPARE_1")
			(options
				(clearance outline)
				(anchor circle)
			)
			(primitives
				(gr_poly
					(pts
						(arc
							(start -0.1778 -0.2794)
							(mid -0.249642 -0.249642)
							(end -0.2794 -0.1778)
						)
						(arc
							(start -0.2794 0.1778)
							(mid -0.249642 0.249642)
							(end -0.1778 0.2794)
						)
						(arc
							(start 0.1778 0.2794)
							(mid 0.249642 0.249642)
							(end 0.2794 0.1778)
						)
						(arc
							(start 0.2794 -0.1778)
							(mid 0.249642 -0.249642)
							(end 0.1778 -0.2794)
						)
					)
					(width 0)
					(fill yes)
				)
			)
		)
		(pad "2" smd custom
			(at 0 0.4445 270)
			(size 0.1397 0.1397)
			(layers "F.Cu" "F.Mask" "F.Paste")
			(net "COMP_SPARE_1_R")
			(options
				(clearance outline)
				(anchor circle)
			)
			(primitives
				(gr_poly
					(pts
						(arc
							(start -0.1778 -0.2794)
							(mid -0.249642 -0.249642)
							(end -0.2794 -0.1778)
						)
						(arc
							(start -0.2794 0.1778)
							(mid -0.249642 0.249642)
							(end -0.1778 0.2794)
						)
						(arc
							(start 0.1778 0.2794)
							(mid 0.249642 0.249642)
							(end 0.2794 0.1778)
						)
						(arc
							(start 0.2794 -0.1778)
							(mid 0.249642 -0.249642)
							(end 0.1778 -0.2794)
						)
					)
					(width 0)
					(fill yes)
				)
			)
		)
	)
	(footprint ""
		(layer "F.Cu")
		(at 222.499936 -109.99978)
		(property "Reference" ""
			(at 0 0 0)
			(layer "F.SilkS")
			(hide yes)
			(effects
				(font
					(size 1.27 1.27)
				)
			)
		)
		(property "Value" "*"
			(at -6.38175 0.19685 0)
			(unlocked yes)
			(layer "F.Fab")
			(hide yes)
			(effects
				(font
					(size 1.016 1.016)
					(thickness 0.1524)
				)
			)
		)
		(duplicate_pad_numbers_are_jumpers no)
		(fp_poly
			(pts
				(arc
					(start 5.0673 0)
					(mid -5.0673 0)
					(end 5.0673 0)
				)
			)
			(stroke
				(width 0)
				(type default)
			)
			(fill no)
			(layer "B.CrtYd")
		)
		(fp_poly
			(pts
				(arc
					(start 5.0673 0)
					(mid -5.0673 0)
					(end 5.0673 0)
				)
			)
			(stroke
				(width 0)
				(type default)
			)
			(fill no)
			(layer "F.CrtYd")
		)
		(fp_poly
			(pts
				(arc
					(start 5.0673 0)
					(mid -5.0673 0)
					(end 5.0673 0)
				)
			)
			(stroke
				(width 0)
				(type default)
			)
			(fill no)
			(layer "B.Fab")
		)
		(fp_poly
			(pts
				(arc
					(start 5.0673 0)
					(mid -5.0673 0)
					(end 5.0673 0)
				)
			)
			(stroke
				(width 0)
				(type default)
			)
			(fill no)
			(layer "F.Fab")
		)
		(pad "1" thru_hole circle
			(at 0 0)
			(size 9.525 9.525)
			(drill 3.5052)
			(layers "*.Cu" "*.Mask")
			(remove_unused_layers no)
			(net "Net_12")
			(clearance -2.5019)
			(thermal_gap 0.3048)
			(padstack
				(mode front_inner_back)
				(layer "Inner"
					(shape circle)
					(size 3.9116 3.9116)
					(clearance 0.3048)
				)
				(layer "B.Cu"
					(shape circle)
					(size 9.525 9.525)
					(clearance -2.5019)
				)
			)
		)
	)
)
